(kicad_pcb
	(version 20260206)
	(generator "pcbnew")
	(generator_version "10.0")
	(general
		(thickness 1.6)
		(legacy_teardrops no)
	)
	(paper "A4")
	(title_block
		(title "01162023_DA0F0TEBIF0_F0T_Expander_BD_F_brd_V02_OCP.brd")
		(comment 1 "Grand Teton / footprints 6890-6895 of 9728")
	)
	(layers
		(0 "F.Cu" signal "TOP")
		(4 "In1.Cu" signal "GND")
		(6 "In2.Cu" signal "VCC")
		(8 "In3.Cu" signal "VCC1")
		(10 "In4.Cu" signal "GND1")
		(12 "In5.Cu" signal "IN1")
		(14 "In6.Cu" signal "GND2")
		(16 "In7.Cu" signal "IN2")
		(18 "In8.Cu" signal "GND3")
		(20 "In9.Cu" signal "IN3")
		(22 "In10.Cu" signal "GND4")
		(24 "In11.Cu" signal "IN4")
		(26 "In12.Cu" signal "GND5")
		(28 "In13.Cu" signal "IN5")
		(30 "In14.Cu" signal "GND6")
		(32 "In15.Cu" signal "IN6")
		(34 "In16.Cu" signal "GND7")
		(2 "B.Cu" signal "BOTTOM")
		(9 "F.Adhes" user "F.Adhesive")
		(11 "B.Adhes" user "B.Adhesive")
		(13 "F.Paste" user "Package Geometry/Pastemask Top")
		(15 "B.Paste" user "Package Geometry/Pastemask Bottom")
		(5 "F.SilkS" user "Ref Des/Silkscreen Top")
		(7 "B.SilkS" user "Ref Des/Silkscreen Bottom")
		(1 "F.Mask" user "Board Geometry/Soldermask Top")
		(3 "B.Mask" user "Board Geometry/Soldermask Bottom")
		(17 "Dwgs.User" user "User.Drawings")
		(19 "Cmts.User" user "User.Comments")
		(21 "Eco1.User" user "User.Eco1")
		(23 "Eco2.User" user "User.Eco2")
		(25 "Edge.Cuts" user "Board Geometry/Outline")
		(27 "Margin" user)
		(31 "F.CrtYd" user "Package Geometry/Place Bound Top")
		(29 "B.CrtYd" user "Package Geometry/Place Bound Bottom")
		(35 "F.Fab" user "Ref Des/Assembly Top")
		(33 "B.Fab" user "Ref Des/Assembly Bottom")
	)
	(footprint ""
		(layer "F.Cu")
		(at 26.243788 -46.90491)
		(property "Reference" "R509"
			(at 0 0 0)
			(layer "F.SilkS")
			(hide yes)
			(effects
				(font
					(size 1.27 1.27)
				)
			)
		)
		(property "Value" ""
			(at 0 0 0)
			(layer "F.Fab")
			(effects
				(font
					(size 1.27 1.27)
				)
			)
		)
		(duplicate_pad_numbers_are_jumpers no)
		(fp_line
			(start -0.7874 -0.4064)
			(end 0.7874 -0.4064)
			(stroke
				(width 0.1524)
				(type default)
			)
			(layer "F.SilkS")
		)
		(fp_line
			(start -0.7874 0.4064)
			(end -0.7874 -0.4064)
			(stroke
				(width 0.1524)
				(type default)
			)
			(layer "F.SilkS")
		)
		(fp_line
			(start 0.7874 -0.4064)
			(end 0.7874 0.4064)
			(stroke
				(width 0.1524)
				(type default)
			)
			(layer "F.SilkS")
		)
		(fp_line
			(start 0.7874 0.4064)
			(end -0.7874 0.4064)
			(stroke
				(width 0.1524)
				(type default)
			)
			(layer "F.SilkS")
		)
		(fp_line
			(start -0.67945 -0.305054)
			(end -0.12065 -0.305054)
			(stroke
				(width 0.1)
				(type default)
			)
			(layer "F.Fab")
		)
		(fp_line
			(start -0.67945 0.3048)
			(end -0.67945 -0.305054)
			(stroke
				(width 0.1)
				(type default)
			)
			(layer "F.Fab")
		)
		(fp_line
			(start -0.12065 -0.305054)
			(end -0.12065 -0.2794)
			(stroke
				(width 0.1)
				(type default)
			)
			(layer "F.Fab")
		)
		(fp_line
			(start -0.12065 -0.2794)
			(end 0.12065 -0.2794)
			(stroke
				(width 0.1)
				(type default)
			)
			(layer "F.Fab")
		)
		(fp_line
			(start -0.12065 0.2794)
			(end -0.12065 0.3048)
			(stroke
				(width 0.1)
				(type default)
			)
			(layer "F.Fab")
		)
		(fp_line
			(start -0.12065 0.3048)
			(end -0.67945 0.3048)
			(stroke
				(width 0.1)
				(type default)
			)
			(layer "F.Fab")
		)
		(fp_line
			(start 0.120396 0.2794)
			(end -0.12065 0.2794)
			(stroke
				(width 0.1)
				(type default)
			)
			(layer "F.Fab")
		)
		(fp_line
			(start 0.120396 0.3048)
			(end 0.120396 0.2794)
			(stroke
				(width 0.1)
				(type default)
			)
			(layer "F.Fab")
		)
		(fp_line
			(start 0.12065 -0.3048)
			(end 0.67945 -0.3048)
			(stroke
				(width 0.1)
				(type default)
			)
			(layer "F.Fab")
		)
		(fp_line
			(start 0.12065 -0.2794)
			(end 0.12065 -0.3048)
			(stroke
				(width 0.1)
				(type default)
			)
			(layer "F.Fab")
		)
		(fp_line
			(start 0.67945 -0.3048)
			(end 0.67945 0.3048)
			(stroke
				(width 0.1)
				(type default)
			)
			(layer "F.Fab")
		)
		(fp_line
			(start 0.67945 0.3048)
			(end 0.120396 0.3048)
			(stroke
				(width 0.1)
				(type default)
			)
			(layer "F.Fab")
		)
		(pad "1" smd circle
			(at -0.40005 0)
			(size 0 0)
			(layers "F.Cu" "F.Mask" "F.Paste")
			(net "SSD0_ADC_ALERT_N")
		)
		(pad "2" smd circle
			(at 0.40005 0)
			(size 0 0)
			(layers "F.Cu" "F.Mask" "F.Paste")
			(net "SSD_0_7_ADC_ALERT_N")
		)
	)
	(footprint ""
		(layer "F.Cu")
		(at 227.31476 -312.671714)
		(property "Reference" "PC224"
			(at 0 0 0)
			(layer "F.SilkS")
			(hide yes)
			(effects
				(font
					(size 1.27 1.27)
				)
			)
		)
		(property "Value" ""
			(at 0 0 0)
			(layer "F.Fab")
			(effects
				(font
					(size 1.27 1.27)
				)
			)
		)
		(duplicate_pad_numbers_are_jumpers no)
		(fp_line
			(start -1.524 -0.762)
			(end 1.524 -0.762)
			(stroke
				(width 0.1524)
				(type default)
			)
			(layer "F.SilkS")
		)
		(fp_line
			(start -1.524 0.762)
			(end -1.524 -0.762)
			(stroke
				(width 0.1524)
				(type default)
			)
			(layer "F.SilkS")
		)
		(fp_line
			(start 1.524 -0.762)
			(end 1.524 0.762)
			(stroke
				(width 0.1524)
				(type default)
			)
			(layer "F.SilkS")
		)
		(fp_line
			(start 1.524 0.762)
			(end -1.524 0.762)
			(stroke
				(width 0.1524)
				(type default)
			)
			(layer "F.SilkS")
		)
		(fp_line
			(start -1.1049 -0.724916)
			(end -1.1049 0.724916)
			(stroke
				(width 0.1)
				(type default)
			)
			(layer "F.Fab")
		)
		(fp_line
			(start -1.1049 0.724916)
			(end 1.1049 0.724916)
			(stroke
				(width 0.1)
				(type default)
			)
			(layer "F.Fab")
		)
		(fp_line
			(start 1.1049 -0.724916)
			(end -1.1049 -0.724916)
			(stroke
				(width 0.1)
				(type default)
			)
			(layer "F.Fab")
		)
		(fp_line
			(start 1.1049 0.724916)
			(end 1.1049 -0.724916)
			(stroke
				(width 0.1)
				(type default)
			)
			(layer "F.Fab")
		)
		(pad "1" smd rect
			(at -0.889 0 180)
			(size 1.016 1.27)
			(layers "F.Cu" "F.Mask" "F.Paste")
			(net "SW_P12V_P1V25_PEX1_FLT")
		)
		(pad "2" smd rect
			(at 0.889 0 180)
			(size 1.016 1.27)
			(layers "F.Cu" "F.Mask" "F.Paste")
			(net "GND")
		)
	)
	(footprint ""
		(layer "F.Cu")
		(at 211.37118 -120.021858)
		(property "Reference" "PU52"
			(at -0.845312 2.627122 0)
			(unlocked yes)
			(layer "F.SilkS")
			(effects
				(font
					(size 0.7874 0.5842)
					(thickness 0.1524)
				)
				(justify left)
			)
		)
		(property "Value" ""
			(at 0 0 0)
			(layer "F.Fab")
			(effects
				(font
					(size 1.27 1.27)
				)
			)
		)
		(duplicate_pad_numbers_are_jumpers no)
		(fp_line
			(start -1.943608 -1.549908)
			(end 1.943608 -1.549908)
			(stroke
				(width 0.1524)
				(type default)
			)
			(layer "F.SilkS")
		)
		(fp_line
			(start -1.943608 1.549908)
			(end -1.943608 -1.549908)
			(stroke
				(width 0.1524)
				(type default)
			)
			(layer "F.SilkS")
		)
		(fp_line
			(start 1.943608 -1.549908)
			(end 1.943608 1.549908)
			(stroke
				(width 0.1524)
				(type default)
			)
			(layer "F.SilkS")
		)
		(fp_line
			(start 1.943608 1.549908)
			(end -1.943608 1.549908)
			(stroke
				(width 0.1524)
				(type default)
			)
			(layer "F.SilkS")
		)
		(fp_poly
			(pts
				(xy -2.019808 -1.549908) (xy -1.257808 -1.549908) (xy -1.257808 -1.880108) (xy -2.019808 -1.880108)
			)
			(stroke
				(width 0)
				(type default)
			)
			(fill yes)
			(layer "F.SilkS")
		)
		(fp_line
			(start -1.549908 -1.549908)
			(end 1.549908 -1.549908)
			(stroke
				(width 0.1)
				(type default)
			)
			(layer "F.Fab")
		)
		(fp_line
			(start -1.549908 1.549908)
			(end -1.549908 -1.549908)
			(stroke
				(width 0.1)
				(type default)
			)
			(layer "F.Fab")
		)
		(fp_line
			(start 1.549908 -1.549908)
			(end 1.549908 1.549908)
			(stroke
				(width 0.1)
				(type default)
			)
			(layer "F.Fab")
		)
		(fp_line
			(start 1.549908 1.549908)
			(end -1.549908 1.549908)
			(stroke
				(width 0.1)
				(type default)
			)
			(layer "F.Fab")
		)
		(fp_poly
			(pts
				(xy -2.019808 -1.549908) (xy -1.257808 -1.549908) (xy -1.257808 -1.880108) (xy -2.019808 -1.880108)
			)
			(stroke
				(width 0)
				(type default)
			)
			(fill yes)
			(layer "F.Fab")
		)
		(pad "1" smd rect
			(at -1.500124 -1.249934 270)
			(size 0.2794 0.6096)
			(layers "F.Cu" "F.Mask" "F.Paste")
			(net "P3V3_NIC3")
		)
		(pad "2" smd rect
			(at -1.500124 -0.750062 270)
			(size 0.2794 0.6096)
			(layers "F.Cu" "F.Mask" "F.Paste")
			(net "P3V3_NIC3")
		)
		(pad "3" smd rect
			(at -1.500124 -0.249936 270)
			(size 0.2794 0.6096)
			(layers "F.Cu" "F.Mask" "F.Paste")
			(net "P3V3_NIC3")
		)
		(pad "4" smd rect
			(at -1.500124 0.249936 270)
			(size 0.2794 0.6096)
			(layers "F.Cu" "F.Mask" "F.Paste")
			(net "P3V3_NIC3")
		)
		(pad "5" smd rect
			(at -1.500124 0.750062 270)
			(size 0.2794 0.6096)
			(layers "F.Cu" "F.Mask" "F.Paste")
			(net "P3V3_NIC3")
		)
		(pad "6" smd rect
			(at -1.500124 1.249934 270)
			(size 0.2794 0.6096)
			(layers "F.Cu" "F.Mask" "F.Paste")
			(net "GND")
		)
		(pad "7" smd rect
			(at 1.500124 1.249934 270)
			(size 0.2794 0.6096)
			(layers "F.Cu" "F.Mask" "F.Paste")
			(net "P3V3_NIC3_SS")
		)
		(pad "8" smd rect
			(at 1.500124 0.750062 270)
			(size 0.2794 0.6096)
			(layers "F.Cu" "F.Mask" "F.Paste")
			(net "PWRGD_P3V3_NIC3")
		)
		(pad "9" smd rect
			(at 1.500124 0.249936 270)
			(size 0.2794 0.6096)
			(layers "F.Cu" "F.Mask" "F.Paste")
			(net "P3V3_NIC3_OCP")
		)
		(pad "10" smd rect
			(at 1.500124 -0.249936 270)
			(size 0.2794 0.6096)
			(layers "F.Cu" "F.Mask" "F.Paste")
			(net "P5V_AUX")
		)
		(pad "11" smd rect
			(at 1.500124 -0.750062 270)
			(size 0.2794 0.6096)
			(layers "F.Cu" "F.Mask" "F.Paste")
			(net "HP_NIC3_EN")
		)
		(pad "12" smd rect
			(at 1.500124 -1.249934 270)
			(size 0.2794 0.6096)
			(layers "F.Cu" "F.Mask" "F.Paste")
			(net "P3V3_AUX")
		)
		(pad "13" smd rect
			(at 0 0)
			(size 1.9812 2.7178)
			(layers "F.Cu" "F.Mask" "F.Paste")
			(net "P3V3_AUX")
		)
		(zone
			(layer "F.Cu")
			(hatch none 0.5)
			(connect_pads
				(clearance 0)
			)
			(min_thickness 0.25)
			(keepout
				(tracks not_allowed)
				(vias allowed)
				(pads allowed)
				(copperpour not_allowed)
				(footprints allowed)
			)
			(placement
				(enabled no)
				(sheetname "")
			)
			(fill
				(thermal_gap 0.5)
				(thermal_bridge_width 0.5)
				(island_removal_mode 0)
			)
			(polygon
				(pts
					(xy 212.51418 -121.571258) (xy 212.51418 -121.444258) (xy 212.51418 -118.472458) (xy 212.51418 -118.47195)
					(xy 210.22818 -118.47195) (xy 210.22818 -118.472458) (xy 210.22818 -118.599458) (xy 210.22818 -120.021858)
					(xy 210.32978 -120.021858) (xy 210.32978 -118.599458) (xy 212.41258 -118.599458) (xy 212.41258 -121.444258)
					(xy 210.32978 -121.444258) (xy 210.32978 -120.047258) (xy 210.22818 -120.047258) (xy 210.22818 -121.444258)
					(xy 210.22818 -121.571258) (xy 210.22818 -121.571766) (xy 212.51418 -121.571766)
				)
			)
		)
	)
	(footprint ""
		(layer "F.Cu")
		(at 219.825316 -122.758962)
		(property "Reference" "R5957"
			(at 0 0 0)
			(layer "F.SilkS")
			(hide yes)
			(effects
				(font
					(size 1.27 1.27)
				)
			)
		)
		(property "Value" ""
			(at 0 0 0)
			(layer "F.Fab")
			(effects
				(font
					(size 1.27 1.27)
				)
			)
		)
		(duplicate_pad_numbers_are_jumpers no)
		(fp_line
			(start -0.7874 -0.4064)
			(end 0.7874 -0.4064)
			(stroke
				(width 0.1524)
				(type default)
			)
			(layer "F.SilkS")
		)
		(fp_line
			(start -0.7874 0.4064)
			(end -0.7874 -0.4064)
			(stroke
				(width 0.1524)
				(type default)
			)
			(layer "F.SilkS")
		)
		(fp_line
			(start 0.7874 -0.4064)
			(end 0.7874 0.4064)
			(stroke
				(width 0.1524)
				(type default)
			)
			(layer "F.SilkS")
		)
		(fp_line
			(start 0.7874 0.4064)
			(end -0.7874 0.4064)
			(stroke
				(width 0.1524)
				(type default)
			)
			(layer "F.SilkS")
		)
		(fp_line
			(start -0.67945 -0.305054)
			(end -0.12065 -0.305054)
			(stroke
				(width 0.1)
				(type default)
			)
			(layer "F.Fab")
		)
		(fp_line
			(start -0.67945 0.3048)
			(end -0.67945 -0.305054)
			(stroke
				(width 0.1)
				(type default)
			)
			(layer "F.Fab")
		)
		(fp_line
			(start -0.12065 -0.305054)
			(end -0.12065 -0.2794)
			(stroke
				(width 0.1)
				(type default)
			)
			(layer "F.Fab")
		)
		(fp_line
			(start -0.12065 -0.2794)
			(end 0.12065 -0.2794)
			(stroke
				(width 0.1)
				(type default)
			)
			(layer "F.Fab")
		)
		(fp_line
			(start -0.12065 0.2794)
			(end -0.12065 0.3048)
			(stroke
				(width 0.1)
				(type default)
			)
			(layer "F.Fab")
		)
		(fp_line
			(start -0.12065 0.3048)
			(end -0.67945 0.3048)
			(stroke
				(width 0.1)
				(type default)
			)
			(layer "F.Fab")
		)
		(fp_line
			(start 0.120396 0.2794)
			(end -0.12065 0.2794)
			(stroke
				(width 0.1)
				(type default)
			)
			(layer "F.Fab")
		)
		(fp_line
			(start 0.120396 0.3048)
			(end 0.120396 0.2794)
			(stroke
				(width 0.1)
				(type default)
			)
			(layer "F.Fab")
		)
		(fp_line
			(start 0.12065 -0.3048)
			(end 0.67945 -0.3048)
			(stroke
				(width 0.1)
				(type default)
			)
			(layer "F.Fab")
		)
		(fp_line
			(start 0.12065 -0.2794)
			(end 0.12065 -0.3048)
			(stroke
				(width 0.1)
				(type default)
			)
			(layer "F.Fab")
		)
		(fp_line
			(start 0.67945 -0.3048)
			(end 0.67945 0.3048)
			(stroke
				(width 0.1)
				(type default)
			)
			(layer "F.Fab")
		)
		(fp_line
			(start 0.67945 0.3048)
			(end 0.120396 0.3048)
			(stroke
				(width 0.1)
				(type default)
			)
			(layer "F.Fab")
		)
		(pad "1" smd circle
			(at -0.40005 0)
			(size 0 0)
			(layers "F.Cu" "F.Mask" "F.Paste")
			(net "P3V3_AUX")
		)
		(pad "2" smd circle
			(at 0.40005 0)
			(size 0 0)
			(layers "F.Cu" "F.Mask" "F.Paste")
			(net "PWRGD_P3V3_NIC3_D")
		)
	)
	(footprint ""
		(layer "F.Cu")
		(at 83.293966 -35.264852)
		(property "Reference" "R5659"
			(at 0 0 0)
			(layer "F.SilkS")
			(hide yes)
			(effects
				(font
					(size 1.27 1.27)
				)
			)
		)
		(property "Value" ""
			(at 0 0 0)
			(layer "F.Fab")
			(effects
				(font
					(size 1.27 1.27)
				)
			)
		)
		(duplicate_pad_numbers_are_jumpers no)
		(fp_line
			(start -0.7874 -0.4064)
			(end 0.7874 -0.4064)
			(stroke
				(width 0.1524)
				(type default)
			)
			(layer "F.SilkS")
		)
		(fp_line
			(start -0.7874 0.4064)
			(end -0.7874 -0.4064)
			(stroke
				(width 0.1524)
				(type default)
			)
			(layer "F.SilkS")
		)
		(fp_line
			(start 0.7874 -0.4064)
			(end 0.7874 0.4064)
			(stroke
				(width 0.1524)
				(type default)
			)
			(layer "F.SilkS")
		)
		(fp_line
			(start 0.7874 0.4064)
			(end -0.7874 0.4064)
			(stroke
				(width 0.1524)
				(type default)
			)
			(layer "F.SilkS")
		)
		(fp_line
			(start -0.67945 -0.305054)
			(end -0.12065 -0.305054)
			(stroke
				(width 0.1)
				(type default)
			)
			(layer "F.Fab")
		)
		(fp_line
			(start -0.67945 0.3048)
			(end -0.67945 -0.305054)
			(stroke
				(width 0.1)
				(type default)
			)
			(layer "F.Fab")
		)
		(fp_line
			(start -0.12065 -0.305054)
			(end -0.12065 -0.2794)
			(stroke
				(width 0.1)
				(type default)
			)
			(layer "F.Fab")
		)
		(fp_line
			(start -0.12065 -0.2794)
			(end 0.12065 -0.2794)
			(stroke
				(width 0.1)
				(type default)
			)
			(layer "F.Fab")
		)
		(fp_line
			(start -0.12065 0.2794)
			(end -0.12065 0.3048)
			(stroke
				(width 0.1)
				(type default)
			)
			(layer "F.Fab")
		)
		(fp_line
			(start -0.12065 0.3048)
			(end -0.67945 0.3048)
			(stroke
				(width 0.1)
				(type default)
			)
			(layer "F.Fab")
		)
		(fp_line
			(start 0.120396 0.2794)
			(end -0.12065 0.2794)
			(stroke
				(width 0.1)
				(type default)
			)
			(layer "F.Fab")
		)
		(fp_line
			(start 0.120396 0.3048)
			(end 0.120396 0.2794)
			(stroke
				(width 0.1)
				(type default)
			)
			(layer "F.Fab")
		)
		(fp_line
			(start 0.12065 -0.3048)
			(end 0.67945 -0.3048)
			(stroke
				(width 0.1)
				(type default)
			)
			(layer "F.Fab")
		)
		(fp_line
			(start 0.12065 -0.2794)
			(end 0.12065 -0.3048)
			(stroke
				(width 0.1)
				(type default)
			)
			(layer "F.Fab")
		)
		(fp_line
			(start 0.67945 -0.3048)
			(end 0.67945 0.3048)
			(stroke
				(width 0.1)
				(type default)
			)
			(layer "F.Fab")
		)
		(fp_line
			(start 0.67945 0.3048)
			(end 0.120396 0.3048)
			(stroke
				(width 0.1)
				(type default)
			)
			(layer "F.Fab")
		)
		(pad "1" smd circle
			(at -0.40005 0)
			(size 0 0)
			(layers "F.Cu" "F.Mask" "F.Paste")
			(net "RST_SMB_SSD3_ISO_N")
		)
		(pad "2" smd circle
			(at 0.40005 0)
			(size 0 0)
			(layers "F.Cu" "F.Mask" "F.Paste")
			(net "GND")
		)
	)
	(footprint ""
		(layer "F.Cu")
		(at 324.589648 -298.885102 -90)
		(property "Reference" "R3973"
			(at 0 0 270)
			(layer "F.SilkS")
			(hide yes)
			(effects
				(font
					(size 1.27 1.27)
				)
			)
		)
		(property "Value" ""
			(at 0 0 270)
			(layer "F.Fab")
			(effects
				(font
					(size 1.27 1.27)
				)
			)
		)
		(duplicate_pad_numbers_are_jumpers no)
		(fp_line
			(start -0.7874 0.4064)
			(end -0.7874 -0.4064)
			(stroke
				(width 0.1524)
				(type default)
			)
			(layer "F.SilkS")
		)
		(fp_line
			(start 0.7874 0.4064)
			(end -0.7874 0.4064)
			(stroke
				(width 0.1524)
				(type default)
			)
			(layer "F.SilkS")
		)
		(fp_line
			(start -0.7874 -0.4064)
			(end 0.7874 -0.4064)
			(stroke
				(width 0.1524)
				(type default)
			)
			(layer "F.SilkS")
		)
		(fp_line
			(start 0.7874 -0.4064)
			(end 0.7874 0.4064)
			(stroke
				(width 0.1524)
				(type default)
			)
			(layer "F.SilkS")
		)
		(fp_line
			(start -0.67945 0.3048)
			(end -0.67945 -0.305054)
			(stroke
				(width 0.1)
				(type default)
			)
			(layer "F.Fab")
		)
		(fp_line
			(start -0.12065 0.3048)
			(end -0.67945 0.3048)
			(stroke
				(width 0.1)
				(type default)
			)
			(layer "F.Fab")
		)
		(fp_line
			(start 0.120396 0.3048)
			(end 0.120396 0.2794)
			(stroke
				(width 0.1)
				(type default)
			)
			(layer "F.Fab")
		)
		(fp_line
			(start 0.67945 0.3048)
			(end 0.120396 0.3048)
			(stroke
				(width 0.1)
				(type default)
			)
			(layer "F.Fab")
		)
		(fp_line
			(start -0.12065 0.2794)
			(end -0.12065 0.3048)
			(stroke
				(width 0.1)
				(type default)
			)
			(layer "F.Fab")
		)
		(fp_line
			(start 0.120396 0.2794)
			(end -0.12065 0.2794)
			(stroke
				(width 0.1)
				(type default)
			)
			(layer "F.Fab")
		)
		(fp_line
			(start -0.12065 -0.2794)
			(end 0.12065 -0.2794)
			(stroke
				(width 0.1)
				(type default)
			)
			(layer "F.Fab")
		)
		(fp_line
			(start 0.12065 -0.2794)
			(end 0.12065 -0.3048)
			(stroke
				(width 0.1)
				(type default)
			)
			(layer "F.Fab")
		)
		(fp_line
			(start 0.12065 -0.3048)
			(end 0.67945 -0.3048)
			(stroke
				(width 0.1)
				(type default)
			)
			(layer "F.Fab")
		)
		(fp_line
			(start 0.67945 -0.3048)
			(end 0.67945 0.3048)
			(stroke
				(width 0.1)
				(type default)
			)
			(layer "F.Fab")
		)
		(fp_line
			(start -0.67945 -0.305054)
			(end -0.12065 -0.305054)
			(stroke
				(width 0.1)
				(type default)
			)
			(layer "F.Fab")
		)
		(fp_line
			(start -0.12065 -0.305054)
			(end -0.12065 -0.2794)
			(stroke
				(width 0.1)
				(type default)
			)
			(layer "F.Fab")
		)
		(pad "1" smd circle
			(at -0.40005 0 270)
			(size 0 0)
			(layers "F.Cu" "F.Mask" "F.Paste")
			(net "I2C_PEX2_HOST_SCL")
		)
		(pad "2" smd circle
			(at 0.40005 0 270)
			(size 0 0)
			(layers "F.Cu" "F.Mask" "F.Paste")
			(net "I2C_PEX2_HOST_R_SCL")
		)
	)
)
